# S9S_MB_2U (Grand Teton) — schematic netlist excerpt (pin names and nets, part order shuffled) for the footprints in the layout excerpt that follows; sources: Cadence DE-HDL packaged netlist, KiCad conversion of 03242023_DA0F0TMBIJ0_F0T_Motherboard_J_brd_V01_OCP.brd

PR587  Q_RES  100 1% CHIP  pkg 0402LF  page 266 : A = VSENSE_PVCCFA_EHV_FIVRA_CPU0_DP ; B = PVCCFA_EHV_FIVRA_CPU0
R1404  Q_RES  2K 1% CHIP  pkg 0402LF  page 219 : A = FM_PCH_P1V8_AUX_EN ; B = GND

(kicad_pcb
	(version 20260206)
	(generator "pcbnew")
	(generator_version "10.0")
	(general
		(thickness 1.6)
		(legacy_teardrops no)
	)
	(paper "A4")
	(title_block
		(title "03242023_DA0F0TMBIJ0_F0T_Motherboard_J_brd_V01_OCP.brd")
		(comment 1 "Grand Teton / footprints 1532-1533 of 6105")
	)
	(layers
		(0 "F.Cu" signal "TOP")
		(4 "In1.Cu" signal "GND")
		(6 "In2.Cu" signal "IN1")
		(8 "In3.Cu" signal "GND1")
		(10 "In4.Cu" signal "IN2")
		(12 "In5.Cu" signal "GND2")
		(14 "In6.Cu" signal "IN3")
		(16 "In7.Cu" signal "GND3")
		(18 "In8.Cu" signal "VCC")
		(20 "In9.Cu" signal "VCC1")
		(22 "In10.Cu" signal "GND4")
		(24 "In11.Cu" signal "IN4")
		(26 "In12.Cu" signal "GND5")
		(28 "In13.Cu" signal "IN5")
		(30 "In14.Cu" signal "GND6")
		(32 "In15.Cu" signal "IN6")
		(34 "In16.Cu" signal "GND7")
		(2 "B.Cu" signal "BOTTOM")
		(9 "F.Adhes" user "F.Adhesive")
		(11 "B.Adhes" user "B.Adhesive")
		(13 "F.Paste" user "Package Geometry/Pastemask Top")
		(15 "B.Paste" user "Package Geometry/Pastemask Bottom")
		(5 "F.SilkS" user "Ref Des/Silkscreen Top")
		(7 "B.SilkS" user "Ref Des/Silkscreen Bottom")
		(1 "F.Mask" user "Board Geometry/Soldermask Top")
		(3 "B.Mask" user "Board Geometry/Soldermask Bottom")
		(17 "Dwgs.User" user "User.Drawings")
		(19 "Cmts.User" user "User.Comments")
		(21 "Eco1.User" user "User.Eco1")
		(23 "Eco2.User" user "User.Eco2")
		(25 "Edge.Cuts" user "Board Geometry/Outline")
		(27 "Margin" user)
		(31 "F.CrtYd" user "Package Geometry/Place Bound Top")
		(29 "B.CrtYd" user "Package Geometry/Place Bound Bottom")
		(35 "F.Fab" user "Ref Des/Assembly Top")
		(33 "B.Fab" user "Ref Des/Assembly Bottom")
	)
	(footprint ""
		(layer "F.Cu")
		(at 172.77588 -126.964948 90)
		(property "Reference" "R1404"
			(at 0 0 90)
			(layer "F.SilkS")
			(hide yes)
			(effects
				(font
					(size 1.27 1.27)
				)
			)
		)
		(property "Value" ""
			(at 0 0 90)
			(layer "F.Fab")
			(effects
				(font
					(size 1.27 1.27)
				)
			)
		)
		(duplicate_pad_numbers_are_jumpers no)
		(fp_line
			(start 0.7874 -0.4064)
			(end 0.7874 0.4064)
			(stroke
				(width 0.1524)
				(type default)
			)
			(layer "F.SilkS")
		)
		(fp_line
			(start -0.7874 -0.4064)
			(end 0.7874 -0.4064)
			(stroke
				(width 0.1524)
				(type default)
			)
			(layer "F.SilkS")
		)
		(fp_line
			(start 0.7874 0.4064)
			(end -0.7874 0.4064)
			(stroke
				(width 0.1524)
				(type default)
			)
			(layer "F.SilkS")
		)
		(fp_line
			(start -0.7874 0.4064)
			(end -0.7874 -0.4064)
			(stroke
				(width 0.1524)
				(type default)
			)
			(layer "F.SilkS")
		)
		(fp_line
			(start -0.12065 -0.305054)
			(end -0.12065 -0.2794)
			(stroke
				(width 0.1)
				(type default)
			)
			(layer "F.Fab")
		)
		(fp_line
			(start -0.67945 -0.305054)
			(end -0.12065 -0.305054)
			(stroke
				(width 0.1)
				(type default)
			)
			(layer "F.Fab")
		)
		(fp_line
			(start 0.67945 -0.3048)
			(end 0.67945 0.3048)
			(stroke
				(width 0.1)
				(type default)
			)
			(layer "F.Fab")
		)
		(fp_line
			(start 0.12065 -0.3048)
			(end 0.67945 -0.3048)
			(stroke
				(width 0.1)
				(type default)
			)
			(layer "F.Fab")
		)
		(fp_line
			(start 0.12065 -0.2794)
			(end 0.12065 -0.3048)
			(stroke
				(width 0.1)
				(type default)
			)
			(layer "F.Fab")
		)
		(fp_line
			(start -0.12065 -0.2794)
			(end 0.12065 -0.2794)
			(stroke
				(width 0.1)
				(type default)
			)
			(layer "F.Fab")
		)
		(fp_line
			(start 0.120396 0.2794)
			(end -0.12065 0.2794)
			(stroke
				(width 0.1)
				(type default)
			)
			(layer "F.Fab")
		)
		(fp_line
			(start -0.12065 0.2794)
			(end -0.12065 0.3048)
			(stroke
				(width 0.1)
				(type default)
			)
			(layer "F.Fab")
		)
		(fp_line
			(start 0.67945 0.3048)
			(end 0.120396 0.3048)
			(stroke
				(width 0.1)
				(type default)
			)
			(layer "F.Fab")
		)
		(fp_line
			(start 0.120396 0.3048)
			(end 0.120396 0.2794)
			(stroke
				(width 0.1)
				(type default)
			)
			(layer "F.Fab")
		)
		(fp_line
			(start -0.12065 0.3048)
			(end -0.67945 0.3048)
			(stroke
				(width 0.1)
				(type default)
			)
			(layer "F.Fab")
		)
		(fp_line
			(start -0.67945 0.3048)
			(end -0.67945 -0.305054)
			(stroke
				(width 0.1)
				(type default)
			)
			(layer "F.Fab")
		)
		(pad "1" smd circle
			(at -0.40005 0 90)
			(size 0 0)
			(layers "F.Cu" "F.Mask" "F.Paste")
			(net "FM_PCH_P1V8_AUX_EN")
		)
		(pad "2" smd circle
			(at 0.40005 0 90)
			(size 0 0)
			(layers "F.Cu" "F.Mask" "F.Paste")
			(net "GND")
		)
	)
	(footprint ""
		(layer "F.Cu")
		(at 303.65573 -346.239084 180)
		(property "Reference" "PR587"
			(at 0 0 180)
			(layer "F.SilkS")
			(hide yes)
			(effects
				(font
					(size 1.27 1.27)
				)
			)
		)
		(property "Value" ""
			(at 0 0 180)
			(layer "F.Fab")
			(effects
				(font
					(size 1.27 1.27)
				)
			)
		)
		(duplicate_pad_numbers_are_jumpers no)
		(fp_line
			(start 0.7874 0.4064)
			(end -0.7874 0.4064)
			(stroke
				(width 0.1524)
				(type default)
			)
			(layer "F.SilkS")
		)
		(fp_line
			(start 0.7874 -0.4064)
			(end 0.7874 0.4064)
			(stroke
				(width 0.1524)
				(type default)
			)
			(layer "F.SilkS")
		)
		(fp_line
			(start -0.7874 0.4064)
			(end -0.7874 -0.4064)
			(stroke
				(width 0.1524)
				(type default)
			)
			(layer "F.SilkS")
		)
		(fp_line
			(start -0.7874 -0.4064)
			(end 0.7874 -0.4064)
			(stroke
				(width 0.1524)
				(type default)
			)
			(layer "F.SilkS")
		)
		(fp_line
			(start 0.67945 0.3048)
			(end 0.120396 0.3048)
			(stroke
				(width 0.1)
				(type default)
			)
			(layer "F.Fab")
		)
		(fp_line
			(start 0.67945 -0.3048)
			(end 0.67945 0.3048)
			(stroke
				(width 0.1)
				(type default)
			)
			(layer "F.Fab")
		)
		(fp_line
			(start 0.12065 -0.2794)
			(end 0.12065 -0.3048)
			(stroke
				(width 0.1)
				(type default)
			)
			(layer "F.Fab")
		)
		(fp_line
			(start 0.12065 -0.3048)
			(end 0.67945 -0.3048)
			(stroke
				(width 0.1)
				(type default)
			)
			(layer "F.Fab")
		)
		(fp_line
			(start 0.120396 0.3048)
			(end 0.120396 0.2794)
			(stroke
				(width 0.1)
				(type default)
			)
			(layer "F.Fab")
		)
		(fp_line
			(start 0.120396 0.2794)
			(end -0.12065 0.2794)
			(stroke
				(width 0.1)
				(type default)
			)
			(layer "F.Fab")
		)
		(fp_line
			(start -0.12065 0.3048)
			(end -0.67945 0.3048)
			(stroke
				(width 0.1)
				(type default)
			)
			(layer "F.Fab")
		)
		(fp_line
			(start -0.12065 0.2794)
			(end -0.12065 0.3048)
			(stroke
				(width 0.1)
				(type default)
			)
			(layer "F.Fab")
		)
		(fp_line
			(start -0.12065 -0.2794)
			(end 0.12065 -0.2794)
			(stroke
				(width 0.1)
				(type default)
			)
			(layer "F.Fab")
		)
		(fp_line
			(start -0.12065 -0.305054)
			(end -0.12065 -0.2794)
			(stroke
				(width 0.1)
				(type default)
			)
			(layer "F.Fab")
		)
		(fp_line
			(start -0.67945 0.3048)
			(end -0.67945 -0.305054)
			(stroke
				(width 0.1)
				(type default)
			)
			(layer "F.Fab")
		)
		(fp_line
			(start -0.67945 -0.305054)
			(end -0.12065 -0.305054)
			(stroke
				(width 0.1)
				(type default)
			)
			(layer "F.Fab")
		)
		(pad "1" smd circle
			(at -0.40005 0 180)
			(size 0 0)
			(layers "F.Cu" "F.Mask" "F.Paste")
			(net "VSENSE_PVCCFA_EHV_FIVRA_CPU0_DP")
		)
		(pad "2" smd circle
			(at 0.40005 0 180)
			(size 0 0)
			(layers "F.Cu" "F.Mask" "F.Paste")
			(net "PVCCFA_EHV_FIVRA_CPU0")
		)
	)
)
